(kicad_pcb
	(version 20260206)
	(generator "pcbnew")
	(generator_version "10.0")
	(general
		(thickness 1.6)
		(legacy_teardrops no)
	)
	(paper "A4")
	(title_block
		(title "01162023_DA0F0TEBIF0_F0T_Expander_BD_F_brd_V02_OCP.brd")
		(comment 1 "Grand Teton / footprints 1782-1788 of 9728")
	)
	(layers
		(0 "F.Cu" signal "TOP")
		(4 "In1.Cu" signal "GND")
		(6 "In2.Cu" signal "VCC")
		(8 "In3.Cu" signal "VCC1")
		(10 "In4.Cu" signal "GND1")
		(12 "In5.Cu" signal "IN1")
		(14 "In6.Cu" signal "GND2")
		(16 "In7.Cu" signal "IN2")
		(18 "In8.Cu" signal "GND3")
		(20 "In9.Cu" signal "IN3")
		(22 "In10.Cu" signal "GND4")
		(24 "In11.Cu" signal "IN4")
		(26 "In12.Cu" signal "GND5")
		(28 "In13.Cu" signal "IN5")
		(30 "In14.Cu" signal "GND6")
		(32 "In15.Cu" signal "IN6")
		(34 "In16.Cu" signal "GND7")
		(2 "B.Cu" signal "BOTTOM")
		(9 "F.Adhes" user "F.Adhesive")
		(11 "B.Adhes" user "B.Adhesive")
		(13 "F.Paste" user "Package Geometry/Pastemask Top")
		(15 "B.Paste" user "Package Geometry/Pastemask Bottom")
		(5 "F.SilkS" user "Ref Des/Silkscreen Top")
		(7 "B.SilkS" user "Ref Des/Silkscreen Bottom")
		(1 "F.Mask" user "Board Geometry/Soldermask Top")
		(3 "B.Mask" user "Board Geometry/Soldermask Bottom")
		(17 "Dwgs.User" user "User.Drawings")
		(19 "Cmts.User" user "User.Comments")
		(21 "Eco1.User" user "User.Eco1")
		(23 "Eco2.User" user "User.Eco2")
		(25 "Edge.Cuts" user "Board Geometry/Outline")
		(27 "Margin" user)
		(31 "F.CrtYd" user "Package Geometry/Place Bound Top")
		(29 "B.CrtYd" user "Package Geometry/Place Bound Bottom")
		(35 "F.Fab" user "Ref Des/Assembly Top")
		(33 "B.Fab" user "Ref Des/Assembly Bottom")
	)
	(footprint ""
		(layer "F.Cu")
		(at 363.474 -195.707)
		(property "Reference" "R4662"
			(at 0 0 0)
			(layer "F.SilkS")
			(hide yes)
			(effects
				(font
					(size 1.27 1.27)
				)
			)
		)
		(property "Value" ""
			(at 0 0 0)
			(layer "F.Fab")
			(effects
				(font
					(size 1.27 1.27)
				)
			)
		)
		(duplicate_pad_numbers_are_jumpers no)
		(fp_line
			(start -0.7874 -0.4064)
			(end 0.7874 -0.4064)
			(stroke
				(width 0.1524)
				(type default)
			)
			(layer "F.SilkS")
		)
		(fp_line
			(start -0.7874 0.4064)
			(end -0.7874 -0.4064)
			(stroke
				(width 0.1524)
				(type default)
			)
			(layer "F.SilkS")
		)
		(fp_line
			(start 0.7874 -0.4064)
			(end 0.7874 0.4064)
			(stroke
				(width 0.1524)
				(type default)
			)
			(layer "F.SilkS")
		)
		(fp_line
			(start 0.7874 0.4064)
			(end -0.7874 0.4064)
			(stroke
				(width 0.1524)
				(type default)
			)
			(layer "F.SilkS")
		)
		(fp_line
			(start -0.67945 -0.305054)
			(end -0.12065 -0.305054)
			(stroke
				(width 0.1)
				(type default)
			)
			(layer "F.Fab")
		)
		(fp_line
			(start -0.67945 0.3048)
			(end -0.67945 -0.305054)
			(stroke
				(width 0.1)
				(type default)
			)
			(layer "F.Fab")
		)
		(fp_line
			(start -0.12065 -0.305054)
			(end -0.12065 -0.2794)
			(stroke
				(width 0.1)
				(type default)
			)
			(layer "F.Fab")
		)
		(fp_line
			(start -0.12065 -0.2794)
			(end 0.12065 -0.2794)
			(stroke
				(width 0.1)
				(type default)
			)
			(layer "F.Fab")
		)
		(fp_line
			(start -0.12065 0.2794)
			(end -0.12065 0.3048)
			(stroke
				(width 0.1)
				(type default)
			)
			(layer "F.Fab")
		)
		(fp_line
			(start -0.12065 0.3048)
			(end -0.67945 0.3048)
			(stroke
				(width 0.1)
				(type default)
			)
			(layer "F.Fab")
		)
		(fp_line
			(start 0.120396 0.2794)
			(end -0.12065 0.2794)
			(stroke
				(width 0.1)
				(type default)
			)
			(layer "F.Fab")
		)
		(fp_line
			(start 0.120396 0.3048)
			(end 0.120396 0.2794)
			(stroke
				(width 0.1)
				(type default)
			)
			(layer "F.Fab")
		)
		(fp_line
			(start 0.12065 -0.3048)
			(end 0.67945 -0.3048)
			(stroke
				(width 0.1)
				(type default)
			)
			(layer "F.Fab")
		)
		(fp_line
			(start 0.12065 -0.2794)
			(end 0.12065 -0.3048)
			(stroke
				(width 0.1)
				(type default)
			)
			(layer "F.Fab")
		)
		(fp_line
			(start 0.67945 -0.3048)
			(end 0.67945 0.3048)
			(stroke
				(width 0.1)
				(type default)
			)
			(layer "F.Fab")
		)
		(fp_line
			(start 0.67945 0.3048)
			(end 0.120396 0.3048)
			(stroke
				(width 0.1)
				(type default)
			)
			(layer "F.Fab")
		)
		(pad "1" smd circle
			(at -0.40005 0)
			(size 0 0)
			(layers "F.Cu" "F.Mask" "F.Paste")
			(net "P3V3_AUX")
		)
		(pad "2" smd circle
			(at 0.40005 0)
			(size 0 0)
			(layers "F.Cu" "F.Mask" "F.Paste")
			(net "SSD5_PEX_PWR_EN_R")
		)
	)
	(footprint ""
		(layer "F.Cu")
		(at 428.319438 -153.390346 180)
		(property "Reference" "C637"
			(at 0 0 180)
			(layer "F.SilkS")
			(hide yes)
			(effects
				(font
					(size 1.27 1.27)
				)
			)
		)
		(property "Value" ""
			(at 0 0 180)
			(layer "F.Fab")
			(effects
				(font
					(size 1.27 1.27)
				)
			)
		)
		(duplicate_pad_numbers_are_jumpers no)
		(fp_line
			(start 0.299974 0.150114)
			(end -0.299974 0.150114)
			(stroke
				(width 0.1)
				(type default)
			)
			(layer "F.Fab")
		)
		(fp_line
			(start 0.299974 -0.150114)
			(end 0.299974 0.150114)
			(stroke
				(width 0.1)
				(type default)
			)
			(layer "F.Fab")
		)
		(fp_line
			(start -0.299974 0.150114)
			(end -0.299974 -0.150114)
			(stroke
				(width 0.1)
				(type default)
			)
			(layer "F.Fab")
		)
		(fp_line
			(start -0.299974 -0.150114)
			(end 0.299974 -0.150114)
			(stroke
				(width 0.1)
				(type default)
			)
			(layer "F.Fab")
		)
		(pad "1" smd rect
			(at -0.2667 0 180)
			(size 0.3048 0.381)
			(layers "F.Cu" "F.Mask" "F.Paste")
			(net "P5E_PEX3_STN0_TX_DP<14>")
		)
		(pad "2" smd rect
			(at 0.2667 0 180)
			(size 0.3048 0.381)
			(layers "F.Cu" "F.Mask" "F.Paste")
			(net "P5E_PEX3_STN0_TX_C_DP<14>")
		)
	)
	(footprint ""
		(layer "F.Cu")
		(at 258.46786 -52.035456 180)
		(property "Reference" "R869"
			(at 0 0 180)
			(layer "F.SilkS")
			(hide yes)
			(effects
				(font
					(size 1.27 1.27)
				)
			)
		)
		(property "Value" ""
			(at 0 0 180)
			(layer "F.Fab")
			(effects
				(font
					(size 1.27 1.27)
				)
			)
		)
		(duplicate_pad_numbers_are_jumpers no)
		(fp_line
			(start 0.7874 0.4064)
			(end -0.7874 0.4064)
			(stroke
				(width 0.1524)
				(type default)
			)
			(layer "F.SilkS")
		)
		(fp_line
			(start 0.7874 -0.4064)
			(end 0.7874 0.4064)
			(stroke
				(width 0.1524)
				(type default)
			)
			(layer "F.SilkS")
		)
		(fp_line
			(start -0.7874 0.4064)
			(end -0.7874 -0.4064)
			(stroke
				(width 0.1524)
				(type default)
			)
			(layer "F.SilkS")
		)
		(fp_line
			(start -0.7874 -0.4064)
			(end 0.7874 -0.4064)
			(stroke
				(width 0.1524)
				(type default)
			)
			(layer "F.SilkS")
		)
		(fp_line
			(start 0.67945 0.3048)
			(end 0.120396 0.3048)
			(stroke
				(width 0.1)
				(type default)
			)
			(layer "F.Fab")
		)
		(fp_line
			(start 0.67945 -0.3048)
			(end 0.67945 0.3048)
			(stroke
				(width 0.1)
				(type default)
			)
			(layer "F.Fab")
		)
		(fp_line
			(start 0.12065 -0.2794)
			(end 0.12065 -0.3048)
			(stroke
				(width 0.1)
				(type default)
			)
			(layer "F.Fab")
		)
		(fp_line
			(start 0.12065 -0.3048)
			(end 0.67945 -0.3048)
			(stroke
				(width 0.1)
				(type default)
			)
			(layer "F.Fab")
		)
		(fp_line
			(start 0.120396 0.3048)
			(end 0.120396 0.2794)
			(stroke
				(width 0.1)
				(type default)
			)
			(layer "F.Fab")
		)
		(fp_line
			(start 0.120396 0.2794)
			(end -0.12065 0.2794)
			(stroke
				(width 0.1)
				(type default)
			)
			(layer "F.Fab")
		)
		(fp_line
			(start -0.12065 0.3048)
			(end -0.67945 0.3048)
			(stroke
				(width 0.1)
				(type default)
			)
			(layer "F.Fab")
		)
		(fp_line
			(start -0.12065 0.2794)
			(end -0.12065 0.3048)
			(stroke
				(width 0.1)
				(type default)
			)
			(layer "F.Fab")
		)
		(fp_line
			(start -0.12065 -0.2794)
			(end 0.12065 -0.2794)
			(stroke
				(width 0.1)
				(type default)
			)
			(layer "F.Fab")
		)
		(fp_line
			(start -0.12065 -0.305054)
			(end -0.12065 -0.2794)
			(stroke
				(width 0.1)
				(type default)
			)
			(layer "F.Fab")
		)
		(fp_line
			(start -0.67945 0.3048)
			(end -0.67945 -0.305054)
			(stroke
				(width 0.1)
				(type default)
			)
			(layer "F.Fab")
		)
		(fp_line
			(start -0.67945 -0.305054)
			(end -0.12065 -0.305054)
			(stroke
				(width 0.1)
				(type default)
			)
			(layer "F.Fab")
		)
		(pad "1" smd circle
			(at -0.40005 0 180)
			(size 0 0)
			(layers "F.Cu" "F.Mask" "F.Paste")
			(net "P3V3_AUX")
		)
		(pad "2" smd circle
			(at 0.40005 0 180)
			(size 0 0)
			(layers "F.Cu" "F.Mask" "F.Paste")
			(net "PWRGD_P12V_SSD8")
		)
	)
	(footprint ""
		(layer "F.Cu")
		(at 418.092382 -31.825184 180)
		(property "Reference" "C717"
			(at 0 0 180)
			(layer "F.SilkS")
			(hide yes)
			(effects
				(font
					(size 1.27 1.27)
				)
			)
		)
		(property "Value" ""
			(at 0 0 180)
			(layer "F.Fab")
			(effects
				(font
					(size 1.27 1.27)
				)
			)
		)
		(duplicate_pad_numbers_are_jumpers no)
		(fp_line
			(start 0.299974 0.150114)
			(end -0.299974 0.150114)
			(stroke
				(width 0.1)
				(type default)
			)
			(layer "F.Fab")
		)
		(fp_line
			(start 0.299974 -0.150114)
			(end 0.299974 0.150114)
			(stroke
				(width 0.1)
				(type default)
			)
			(layer "F.Fab")
		)
		(fp_line
			(start -0.299974 0.150114)
			(end -0.299974 -0.150114)
			(stroke
				(width 0.1)
				(type default)
			)
			(layer "F.Fab")
		)
		(fp_line
			(start -0.299974 -0.150114)
			(end 0.299974 -0.150114)
			(stroke
				(width 0.1)
				(type default)
			)
			(layer "F.Fab")
		)
		(pad "1" smd rect
			(at -0.2667 0 180)
			(size 0.3048 0.381)
			(layers "F.Cu" "F.Mask" "F.Paste")
			(net "P5E_PEX3_STN2_TX_DN<38>")
		)
		(pad "2" smd rect
			(at 0.2667 0 180)
			(size 0.3048 0.381)
			(layers "F.Cu" "F.Mask" "F.Paste")
			(net "P5E_PEX3_STN2_TX_C_DN<38>")
		)
	)
	(footprint ""
		(layer "F.Cu")
		(at 137.622788 -356.244906 90)
		(property "Reference" "C2250"
			(at 0 0 90)
			(layer "F.SilkS")
			(hide yes)
			(effects
				(font
					(size 1.27 1.27)
				)
			)
		)
		(property "Value" ""
			(at 0 0 90)
			(layer "F.Fab")
			(effects
				(font
					(size 1.27 1.27)
				)
			)
		)
		(duplicate_pad_numbers_are_jumpers no)
		(fp_line
			(start 0.299974 -0.150114)
			(end 0.299974 0.150114)
			(stroke
				(width 0.1)
				(type default)
			)
			(layer "F.Fab")
		)
		(fp_line
			(start -0.299974 -0.150114)
			(end 0.299974 -0.150114)
			(stroke
				(width 0.1)
				(type default)
			)
			(layer "F.Fab")
		)
		(fp_line
			(start 0.299974 0.150114)
			(end -0.299974 0.150114)
			(stroke
				(width 0.1)
				(type default)
			)
			(layer "F.Fab")
		)
		(fp_line
			(start -0.299974 0.150114)
			(end -0.299974 -0.150114)
			(stroke
				(width 0.1)
				(type default)
			)
			(layer "F.Fab")
		)
		(pad "1" smd rect
			(at -0.2667 0 90)
			(size 0.3048 0.381)
			(layers "F.Cu" "F.Mask" "F.Paste")
			(net "P5E_PEX1_STN5_TX_DN<92>")
		)
		(pad "2" smd rect
			(at 0.2667 0 90)
			(size 0.3048 0.381)
			(layers "F.Cu" "F.Mask" "F.Paste")
			(net "P5E_PEX1_STN5_TX_C_DN<92>")
		)
	)
	(footprint ""
		(layer "F.Cu")
		(at 363.474 -212.979 180)
		(property "Reference" "R4620"
			(at 0 0 180)
			(layer "F.SilkS")
			(hide yes)
			(effects
				(font
					(size 1.27 1.27)
				)
			)
		)
		(property "Value" ""
			(at 0 0 180)
			(layer "F.Fab")
			(effects
				(font
					(size 1.27 1.27)
				)
			)
		)
		(duplicate_pad_numbers_are_jumpers no)
		(fp_line
			(start 0.7874 0.4064)
			(end -0.7874 0.4064)
			(stroke
				(width 0.1524)
				(type default)
			)
			(layer "F.SilkS")
		)
		(fp_line
			(start 0.7874 -0.4064)
			(end 0.7874 0.4064)
			(stroke
				(width 0.1524)
				(type default)
			)
			(layer "F.SilkS")
		)
		(fp_line
			(start -0.7874 0.4064)
			(end -0.7874 -0.4064)
			(stroke
				(width 0.1524)
				(type default)
			)
			(layer "F.SilkS")
		)
		(fp_line
			(start -0.7874 -0.4064)
			(end 0.7874 -0.4064)
			(stroke
				(width 0.1524)
				(type default)
			)
			(layer "F.SilkS")
		)
		(fp_line
			(start 0.67945 0.3048)
			(end 0.120396 0.3048)
			(stroke
				(width 0.1)
				(type default)
			)
			(layer "F.Fab")
		)
		(fp_line
			(start 0.67945 -0.3048)
			(end 0.67945 0.3048)
			(stroke
				(width 0.1)
				(type default)
			)
			(layer "F.Fab")
		)
		(fp_line
			(start 0.12065 -0.2794)
			(end 0.12065 -0.3048)
			(stroke
				(width 0.1)
				(type default)
			)
			(layer "F.Fab")
		)
		(fp_line
			(start 0.12065 -0.3048)
			(end 0.67945 -0.3048)
			(stroke
				(width 0.1)
				(type default)
			)
			(layer "F.Fab")
		)
		(fp_line
			(start 0.120396 0.3048)
			(end 0.120396 0.2794)
			(stroke
				(width 0.1)
				(type default)
			)
			(layer "F.Fab")
		)
		(fp_line
			(start 0.120396 0.2794)
			(end -0.12065 0.2794)
			(stroke
				(width 0.1)
				(type default)
			)
			(layer "F.Fab")
		)
		(fp_line
			(start -0.12065 0.3048)
			(end -0.67945 0.3048)
			(stroke
				(width 0.1)
				(type default)
			)
			(layer "F.Fab")
		)
		(fp_line
			(start -0.12065 0.2794)
			(end -0.12065 0.3048)
			(stroke
				(width 0.1)
				(type default)
			)
			(layer "F.Fab")
		)
		(fp_line
			(start -0.12065 -0.2794)
			(end 0.12065 -0.2794)
			(stroke
				(width 0.1)
				(type default)
			)
			(layer "F.Fab")
		)
		(fp_line
			(start -0.12065 -0.305054)
			(end -0.12065 -0.2794)
			(stroke
				(width 0.1)
				(type default)
			)
			(layer "F.Fab")
		)
		(fp_line
			(start -0.67945 0.3048)
			(end -0.67945 -0.305054)
			(stroke
				(width 0.1)
				(type default)
			)
			(layer "F.Fab")
		)
		(fp_line
			(start -0.67945 -0.305054)
			(end -0.12065 -0.305054)
			(stroke
				(width 0.1)
				(type default)
			)
			(layer "F.Fab")
		)
		(pad "1" smd circle
			(at -0.40005 0 180)
			(size 0 0)
			(layers "F.Cu" "F.Mask" "F.Paste")
			(net "PCA9555_0_PEX0_A2")
		)
		(pad "2" smd circle
			(at 0.40005 0 180)
			(size 0 0)
			(layers "F.Cu" "F.Mask" "F.Paste")
			(net "P3V3_AUX")
		)
	)
	(footprint ""
		(layer "F.Cu")
		(at 97.633028 -98.968052 -90)
		(property "Reference" "PU24"
			(at 1.748028 2.319274 90)
			(unlocked yes)
			(layer "F.SilkS")
			(effects
				(font
					(size 0.7874 0.5842)
					(thickness 0.1524)
				)
				(justify left)
			)
		)
		(property "Value" ""
			(at 0 0 270)
			(layer "F.Fab")
			(effects
				(font
					(size 1.27 1.27)
				)
			)
		)
		(duplicate_pad_numbers_are_jumpers no)
		(fp_line
			(start -1.943608 1.549908)
			(end -1.943608 -1.549908)
			(stroke
				(width 0.1524)
				(type default)
			)
			(layer "F.SilkS")
		)
		(fp_line
			(start 1.943608 1.549908)
			(end -1.943608 1.549908)
			(stroke
				(width 0.1524)
				(type default)
			)
			(layer "F.SilkS")
		)
		(fp_line
			(start -1.943608 -1.549908)
			(end 1.943608 -1.549908)
			(stroke
				(width 0.1524)
				(type default)
			)
			(layer "F.SilkS")
		)
		(fp_line
			(start 1.943608 -1.549908)
			(end 1.943608 1.549908)
			(stroke
				(width 0.1524)
				(type default)
			)
			(layer "F.SilkS")
		)
		(fp_poly
			(pts
				(xy -2.019808 -1.549908) (xy -1.257808 -1.549908) (xy -1.257808 -1.880108) (xy -2.019808 -1.880108)
			)
			(stroke
				(width 0)
				(type default)
			)
			(fill yes)
			(layer "F.SilkS")
		)
		(fp_line
			(start -1.549908 1.549908)
			(end -1.549908 -1.549908)
			(stroke
				(width 0.1)
				(type default)
			)
			(layer "F.Fab")
		)
		(fp_line
			(start 1.549908 1.549908)
			(end -1.549908 1.549908)
			(stroke
				(width 0.1)
				(type default)
			)
			(layer "F.Fab")
		)
		(fp_line
			(start -1.549908 -1.549908)
			(end 1.549908 -1.549908)
			(stroke
				(width 0.1)
				(type default)
			)
			(layer "F.Fab")
		)
		(fp_line
			(start 1.549908 -1.549908)
			(end 1.549908 1.549908)
			(stroke
				(width 0.1)
				(type default)
			)
			(layer "F.Fab")
		)
		(fp_poly
			(pts
				(xy -2.019808 -1.549908) (xy -1.257808 -1.549908) (xy -1.257808 -1.880108) (xy -2.019808 -1.880108)
			)
			(stroke
				(width 0)
				(type default)
			)
			(fill yes)
			(layer "F.Fab")
		)
		(pad "1" smd rect
			(at -1.500124 -1.249934 180)
			(size 0.2794 0.6096)
			(layers "F.Cu" "F.Mask" "F.Paste")
			(net "P12V_NIC1_R")
		)
		(pad "2" smd rect
			(at -1.500124 -0.750062 180)
			(size 0.2794 0.6096)
			(layers "F.Cu" "F.Mask" "F.Paste")
			(net "P12V_NIC1_R")
		)
		(pad "3" smd rect
			(at -1.500124 -0.249936 180)
			(size 0.2794 0.6096)
			(layers "F.Cu" "F.Mask" "F.Paste")
			(net "P12V_NIC1_R")
		)
		(pad "4" smd rect
			(at -1.500124 0.249936 180)
			(size 0.2794 0.6096)
			(layers "F.Cu" "F.Mask" "F.Paste")
			(net "P12V_NIC1_R")
		)
		(pad "5" smd rect
			(at -1.500124 0.750062 180)
			(size 0.2794 0.6096)
			(layers "F.Cu" "F.Mask" "F.Paste")
			(net "P12V_NIC1_R")
		)
		(pad "6" smd rect
			(at -1.500124 1.249934 180)
			(size 0.2794 0.6096)
			(layers "F.Cu" "F.Mask" "F.Paste")
			(net "GND")
		)
		(pad "7" smd rect
			(at 1.500124 1.249934 180)
			(size 0.2794 0.6096)
			(layers "F.Cu" "F.Mask" "F.Paste")
			(net "P12V_NIC1_SS")
		)
		(pad "8" smd rect
			(at 1.500124 0.750062 180)
			(size 0.2794 0.6096)
			(layers "F.Cu" "F.Mask" "F.Paste")
			(net "PWRGD_P12V_NIC1")
		)
		(pad "9" smd rect
			(at 1.500124 0.249936 180)
			(size 0.2794 0.6096)
			(layers "F.Cu" "F.Mask" "F.Paste")
			(net "P12V_NIC1_OCP")
		)
		(pad "10" smd rect
			(at 1.500124 -0.249936 180)
			(size 0.2794 0.6096)
			(layers "F.Cu" "F.Mask" "F.Paste")
			(net "P5V_AUX")
		)
		(pad "11" smd rect
			(at 1.500124 -0.750062 180)
			(size 0.2794 0.6096)
			(layers "F.Cu" "F.Mask" "F.Paste")
			(net "P12V_NIC1_EN_R")
		)
		(pad "12" smd rect
			(at 1.500124 -1.249934 180)
			(size 0.2794 0.6096)
			(layers "F.Cu" "F.Mask" "F.Paste")
			(net "P12V_AUX")
		)
		(pad "13" smd rect
			(at 0 0 270)
			(size 1.9812 2.7178)
			(layers "F.Cu" "F.Mask" "F.Paste")
			(net "P12V_AUX")
		)
		(zone
			(layer "F.Cu")
			(hatch none 0.5)
			(connect_pads
				(clearance 0)
			)
			(min_thickness 0.25)
			(keepout
				(tracks not_allowed)
				(vias allowed)
				(pads allowed)
				(copperpour not_allowed)
				(footprints allowed)
			)
			(placement
				(enabled no)
				(sheetname "")
			)
			(fill
				(thermal_gap 0.5)
				(thermal_bridge_width 0.5)
				(island_removal_mode 0)
			)
			(polygon
				(pts
					(xy 99.182428 -97.825052) (xy 99.055428 -97.825052) (xy 96.083628 -97.825052) (xy 96.08312 -97.825052)
					(xy 96.08312 -100.111052) (xy 96.083628 -100.111052) (xy 96.210628 -100.111052) (xy 97.633028 -100.111052)
					(xy 97.633028 -100.009452) (xy 96.210628 -100.009452) (xy 96.210628 -97.926652) (xy 99.055428 -97.926652)
					(xy 99.055428 -100.009452) (xy 97.658428 -100.009452) (xy 97.658428 -100.111052) (xy 99.055428 -100.111052)
					(xy 99.182428 -100.111052) (xy 99.182936 -100.111052) (xy 99.182936 -97.825052)
				)
			)
		)
	)
)
